(kicad_pcb
	(version 20260206)
	(generator "pcbnew")
	(generator_version "10.0")
	(general
		(thickness 1.6)
		(legacy_teardrops no)
	)
	(paper "A4")
	(title_block
		(title "03242023_DA0F0TMBIJ0_F0T_Motherboard_J_brd_V01_OCP.brd")
		(comment 1 "Grand Teton / footprints 1237-1243 of 6105")
	)
	(layers
		(0 "F.Cu" signal "TOP")
		(4 "In1.Cu" signal "GND")
		(6 "In2.Cu" signal "IN1")
		(8 "In3.Cu" signal "GND1")
		(10 "In4.Cu" signal "IN2")
		(12 "In5.Cu" signal "GND2")
		(14 "In6.Cu" signal "IN3")
		(16 "In7.Cu" signal "GND3")
		(18 "In8.Cu" signal "VCC")
		(20 "In9.Cu" signal "VCC1")
		(22 "In10.Cu" signal "GND4")
		(24 "In11.Cu" signal "IN4")
		(26 "In12.Cu" signal "GND5")
		(28 "In13.Cu" signal "IN5")
		(30 "In14.Cu" signal "GND6")
		(32 "In15.Cu" signal "IN6")
		(34 "In16.Cu" signal "GND7")
		(2 "B.Cu" signal "BOTTOM")
		(9 "F.Adhes" user "F.Adhesive")
		(11 "B.Adhes" user "B.Adhesive")
		(13 "F.Paste" user "Package Geometry/Pastemask Top")
		(15 "B.Paste" user "Package Geometry/Pastemask Bottom")
		(5 "F.SilkS" user "Ref Des/Silkscreen Top")
		(7 "B.SilkS" user "Ref Des/Silkscreen Bottom")
		(1 "F.Mask" user "Board Geometry/Soldermask Top")
		(3 "B.Mask" user "Board Geometry/Soldermask Bottom")
		(17 "Dwgs.User" user "User.Drawings")
		(19 "Cmts.User" user "User.Comments")
		(21 "Eco1.User" user "User.Eco1")
		(23 "Eco2.User" user "User.Eco2")
		(25 "Edge.Cuts" user "Board Geometry/Outline")
		(27 "Margin" user)
		(31 "F.CrtYd" user "Package Geometry/Place Bound Top")
		(29 "B.CrtYd" user "Package Geometry/Place Bound Bottom")
		(35 "F.Fab" user "Ref Des/Assembly Top")
		(33 "B.Fab" user "Ref Des/Assembly Bottom")
	)
	(footprint ""
		(layer "F.Cu")
		(at 164.29101 -130.526536 -90)
		(property "Reference" "R1643"
			(at 0 0 270)
			(layer "F.SilkS")
			(hide yes)
			(effects
				(font
					(size 1.27 1.27)
				)
			)
		)
		(property "Value" ""
			(at 0 0 270)
			(layer "F.Fab")
			(effects
				(font
					(size 1.27 1.27)
				)
			)
		)
		(duplicate_pad_numbers_are_jumpers no)
		(fp_line
			(start -0.7874 0.4064)
			(end -0.7874 -0.4064)
			(stroke
				(width 0.1524)
				(type default)
			)
			(layer "F.SilkS")
		)
		(fp_line
			(start 0.7874 0.4064)
			(end -0.7874 0.4064)
			(stroke
				(width 0.1524)
				(type default)
			)
			(layer "F.SilkS")
		)
		(fp_line
			(start -0.7874 -0.4064)
			(end 0.7874 -0.4064)
			(stroke
				(width 0.1524)
				(type default)
			)
			(layer "F.SilkS")
		)
		(fp_line
			(start 0.7874 -0.4064)
			(end 0.7874 0.4064)
			(stroke
				(width 0.1524)
				(type default)
			)
			(layer "F.SilkS")
		)
		(fp_line
			(start -0.67945 0.3048)
			(end -0.67945 -0.305054)
			(stroke
				(width 0.1)
				(type default)
			)
			(layer "F.Fab")
		)
		(fp_line
			(start -0.12065 0.3048)
			(end -0.67945 0.3048)
			(stroke
				(width 0.1)
				(type default)
			)
			(layer "F.Fab")
		)
		(fp_line
			(start 0.120396 0.3048)
			(end 0.120396 0.2794)
			(stroke
				(width 0.1)
				(type default)
			)
			(layer "F.Fab")
		)
		(fp_line
			(start 0.67945 0.3048)
			(end 0.120396 0.3048)
			(stroke
				(width 0.1)
				(type default)
			)
			(layer "F.Fab")
		)
		(fp_line
			(start -0.12065 0.2794)
			(end -0.12065 0.3048)
			(stroke
				(width 0.1)
				(type default)
			)
			(layer "F.Fab")
		)
		(fp_line
			(start 0.120396 0.2794)
			(end -0.12065 0.2794)
			(stroke
				(width 0.1)
				(type default)
			)
			(layer "F.Fab")
		)
		(fp_line
			(start -0.12065 -0.2794)
			(end 0.12065 -0.2794)
			(stroke
				(width 0.1)
				(type default)
			)
			(layer "F.Fab")
		)
		(fp_line
			(start 0.12065 -0.2794)
			(end 0.12065 -0.3048)
			(stroke
				(width 0.1)
				(type default)
			)
			(layer "F.Fab")
		)
		(fp_line
			(start 0.12065 -0.3048)
			(end 0.67945 -0.3048)
			(stroke
				(width 0.1)
				(type default)
			)
			(layer "F.Fab")
		)
		(fp_line
			(start 0.67945 -0.3048)
			(end 0.67945 0.3048)
			(stroke
				(width 0.1)
				(type default)
			)
			(layer "F.Fab")
		)
		(fp_line
			(start -0.67945 -0.305054)
			(end -0.12065 -0.305054)
			(stroke
				(width 0.1)
				(type default)
			)
			(layer "F.Fab")
		)
		(fp_line
			(start -0.12065 -0.305054)
			(end -0.12065 -0.2794)
			(stroke
				(width 0.1)
				(type default)
			)
			(layer "F.Fab")
		)
		(pad "1" smd circle
			(at -0.40005 0 270)
			(size 0 0)
			(layers "F.Cu" "F.Mask" "F.Paste")
			(net "P12V_AUX")
		)
		(pad "2" smd circle
			(at 0.40005 0 270)
			(size 0 0)
			(layers "F.Cu" "F.Mask" "F.Paste")
			(net "VR_P5V_EN_N")
		)
	)
	(footprint ""
		(layer "F.Cu")
		(at 105.30713 -241.97691 -90)
		(property "Reference" "C242"
			(at 0 0 270)
			(layer "F.SilkS")
			(hide yes)
			(effects
				(font
					(size 1.27 1.27)
				)
			)
		)
		(property "Value" ""
			(at 0 0 270)
			(layer "F.Fab")
			(effects
				(font
					(size 1.27 1.27)
				)
			)
		)
		(duplicate_pad_numbers_are_jumpers no)
		(fp_line
			(start -0.7874 0.4064)
			(end -0.7874 -0.4064)
			(stroke
				(width 0.1524)
				(type default)
			)
			(layer "F.SilkS")
		)
		(fp_line
			(start 0.7874 0.4064)
			(end -0.7874 0.4064)
			(stroke
				(width 0.1524)
				(type default)
			)
			(layer "F.SilkS")
		)
		(fp_line
			(start -0.7874 -0.4064)
			(end 0.7874 -0.4064)
			(stroke
				(width 0.1524)
				(type default)
			)
			(layer "F.SilkS")
		)
		(fp_line
			(start 0.7874 -0.4064)
			(end 0.7874 0.4064)
			(stroke
				(width 0.1524)
				(type default)
			)
			(layer "F.SilkS")
		)
		(fp_line
			(start -0.67945 0.3048)
			(end -0.67945 -0.305054)
			(stroke
				(width 0.1)
				(type default)
			)
			(layer "F.Fab")
		)
		(fp_line
			(start -0.12065 0.3048)
			(end -0.67945 0.3048)
			(stroke
				(width 0.1)
				(type default)
			)
			(layer "F.Fab")
		)
		(fp_line
			(start 0.120396 0.3048)
			(end 0.120396 0.2794)
			(stroke
				(width 0.1)
				(type default)
			)
			(layer "F.Fab")
		)
		(fp_line
			(start 0.67945 0.3048)
			(end 0.120396 0.3048)
			(stroke
				(width 0.1)
				(type default)
			)
			(layer "F.Fab")
		)
		(fp_line
			(start -0.12065 0.2794)
			(end -0.12065 0.3048)
			(stroke
				(width 0.1)
				(type default)
			)
			(layer "F.Fab")
		)
		(fp_line
			(start 0.120396 0.2794)
			(end -0.12065 0.2794)
			(stroke
				(width 0.1)
				(type default)
			)
			(layer "F.Fab")
		)
		(fp_line
			(start -0.12065 -0.2794)
			(end 0.12065 -0.2794)
			(stroke
				(width 0.1)
				(type default)
			)
			(layer "F.Fab")
		)
		(fp_line
			(start 0.12065 -0.2794)
			(end 0.12065 -0.3048)
			(stroke
				(width 0.1)
				(type default)
			)
			(layer "F.Fab")
		)
		(fp_line
			(start 0.12065 -0.3048)
			(end 0.67945 -0.3048)
			(stroke
				(width 0.1)
				(type default)
			)
			(layer "F.Fab")
		)
		(fp_line
			(start 0.67945 -0.3048)
			(end 0.67945 0.3048)
			(stroke
				(width 0.1)
				(type default)
			)
			(layer "F.Fab")
		)
		(fp_line
			(start -0.67945 -0.305054)
			(end -0.12065 -0.305054)
			(stroke
				(width 0.1)
				(type default)
			)
			(layer "F.Fab")
		)
		(fp_line
			(start -0.12065 -0.305054)
			(end -0.12065 -0.2794)
			(stroke
				(width 0.1)
				(type default)
			)
			(layer "F.Fab")
		)
		(pad "1" smd circle
			(at -0.40005 0 270)
			(size 0 0)
			(layers "F.Cu" "F.Mask" "F.Paste")
			(net "PVCCIN_CPU1")
		)
		(pad "2" smd circle
			(at 0.40005 0 270)
			(size 0 0)
			(layers "F.Cu" "F.Mask" "F.Paste")
			(net "GND")
		)
	)
	(footprint ""
		(layer "F.Cu")
		(at 157.870144 -53.359304 -90)
		(property "Reference" "C2021"
			(at 0 0 270)
			(layer "F.SilkS")
			(hide yes)
			(effects
				(font
					(size 1.27 1.27)
				)
			)
		)
		(property "Value" ""
			(at 0 0 270)
			(layer "F.Fab")
			(effects
				(font
					(size 1.27 1.27)
				)
			)
		)
		(duplicate_pad_numbers_are_jumpers no)
		(fp_line
			(start -0.7874 0.4064)
			(end -0.7874 -0.4064)
			(stroke
				(width 0.1524)
				(type default)
			)
			(layer "F.SilkS")
		)
		(fp_line
			(start 0.7874 0.4064)
			(end -0.7874 0.4064)
			(stroke
				(width 0.1524)
				(type default)
			)
			(layer "F.SilkS")
		)
		(fp_line
			(start -0.7874 -0.4064)
			(end 0.7874 -0.4064)
			(stroke
				(width 0.1524)
				(type default)
			)
			(layer "F.SilkS")
		)
		(fp_line
			(start 0.7874 -0.4064)
			(end 0.7874 0.4064)
			(stroke
				(width 0.1524)
				(type default)
			)
			(layer "F.SilkS")
		)
		(fp_line
			(start -0.67945 0.3048)
			(end -0.67945 -0.305054)
			(stroke
				(width 0.1)
				(type default)
			)
			(layer "F.Fab")
		)
		(fp_line
			(start -0.12065 0.3048)
			(end -0.67945 0.3048)
			(stroke
				(width 0.1)
				(type default)
			)
			(layer "F.Fab")
		)
		(fp_line
			(start 0.120396 0.3048)
			(end 0.120396 0.2794)
			(stroke
				(width 0.1)
				(type default)
			)
			(layer "F.Fab")
		)
		(fp_line
			(start 0.67945 0.3048)
			(end 0.120396 0.3048)
			(stroke
				(width 0.1)
				(type default)
			)
			(layer "F.Fab")
		)
		(fp_line
			(start -0.12065 0.2794)
			(end -0.12065 0.3048)
			(stroke
				(width 0.1)
				(type default)
			)
			(layer "F.Fab")
		)
		(fp_line
			(start 0.120396 0.2794)
			(end -0.12065 0.2794)
			(stroke
				(width 0.1)
				(type default)
			)
			(layer "F.Fab")
		)
		(fp_line
			(start -0.12065 -0.2794)
			(end 0.12065 -0.2794)
			(stroke
				(width 0.1)
				(type default)
			)
			(layer "F.Fab")
		)
		(fp_line
			(start 0.12065 -0.2794)
			(end 0.12065 -0.3048)
			(stroke
				(width 0.1)
				(type default)
			)
			(layer "F.Fab")
		)
		(fp_line
			(start 0.12065 -0.3048)
			(end 0.67945 -0.3048)
			(stroke
				(width 0.1)
				(type default)
			)
			(layer "F.Fab")
		)
		(fp_line
			(start 0.67945 -0.3048)
			(end 0.67945 0.3048)
			(stroke
				(width 0.1)
				(type default)
			)
			(layer "F.Fab")
		)
		(fp_line
			(start -0.67945 -0.305054)
			(end -0.12065 -0.305054)
			(stroke
				(width 0.1)
				(type default)
			)
			(layer "F.Fab")
		)
		(fp_line
			(start -0.12065 -0.305054)
			(end -0.12065 -0.2794)
			(stroke
				(width 0.1)
				(type default)
			)
			(layer "F.Fab")
		)
		(pad "1" smd circle
			(at -0.40005 0 270)
			(size 0 0)
			(layers "F.Cu" "F.Mask" "F.Paste")
			(net "VSENSE_P12V_INA230_4_INP")
		)
		(pad "2" smd circle
			(at 0.40005 0 270)
			(size 0 0)
			(layers "F.Cu" "F.Mask" "F.Paste")
			(net "VSENSE_P12V_INA230_4_INN")
		)
	)
	(footprint ""
		(layer "F.Cu")
		(at 420.591488 -173.654974 180)
		(property "Reference" "PC1347"
			(at 0 0 180)
			(layer "F.SilkS")
			(hide yes)
			(effects
				(font
					(size 1.27 1.27)
				)
			)
		)
		(property "Value" ""
			(at 0 0 180)
			(layer "F.Fab")
			(effects
				(font
					(size 1.27 1.27)
				)
			)
		)
		(duplicate_pad_numbers_are_jumpers no)
		(fp_line
			(start 0.7874 0.4064)
			(end -0.7874 0.4064)
			(stroke
				(width 0.1524)
				(type default)
			)
			(layer "F.SilkS")
		)
		(fp_line
			(start 0.7874 -0.4064)
			(end 0.7874 0.4064)
			(stroke
				(width 0.1524)
				(type default)
			)
			(layer "F.SilkS")
		)
		(fp_line
			(start -0.7874 0.4064)
			(end -0.7874 -0.4064)
			(stroke
				(width 0.1524)
				(type default)
			)
			(layer "F.SilkS")
		)
		(fp_line
			(start -0.7874 -0.4064)
			(end 0.7874 -0.4064)
			(stroke
				(width 0.1524)
				(type default)
			)
			(layer "F.SilkS")
		)
		(fp_line
			(start 0.67945 0.3048)
			(end 0.120396 0.3048)
			(stroke
				(width 0.1)
				(type default)
			)
			(layer "F.Fab")
		)
		(fp_line
			(start 0.67945 -0.3048)
			(end 0.67945 0.3048)
			(stroke
				(width 0.1)
				(type default)
			)
			(layer "F.Fab")
		)
		(fp_line
			(start 0.12065 -0.2794)
			(end 0.12065 -0.3048)
			(stroke
				(width 0.1)
				(type default)
			)
			(layer "F.Fab")
		)
		(fp_line
			(start 0.12065 -0.3048)
			(end 0.67945 -0.3048)
			(stroke
				(width 0.1)
				(type default)
			)
			(layer "F.Fab")
		)
		(fp_line
			(start 0.120396 0.3048)
			(end 0.120396 0.2794)
			(stroke
				(width 0.1)
				(type default)
			)
			(layer "F.Fab")
		)
		(fp_line
			(start 0.120396 0.2794)
			(end -0.12065 0.2794)
			(stroke
				(width 0.1)
				(type default)
			)
			(layer "F.Fab")
		)
		(fp_line
			(start -0.12065 0.3048)
			(end -0.67945 0.3048)
			(stroke
				(width 0.1)
				(type default)
			)
			(layer "F.Fab")
		)
		(fp_line
			(start -0.12065 0.2794)
			(end -0.12065 0.3048)
			(stroke
				(width 0.1)
				(type default)
			)
			(layer "F.Fab")
		)
		(fp_line
			(start -0.12065 -0.2794)
			(end 0.12065 -0.2794)
			(stroke
				(width 0.1)
				(type default)
			)
			(layer "F.Fab")
		)
		(fp_line
			(start -0.12065 -0.305054)
			(end -0.12065 -0.2794)
			(stroke
				(width 0.1)
				(type default)
			)
			(layer "F.Fab")
		)
		(fp_line
			(start -0.67945 0.3048)
			(end -0.67945 -0.305054)
			(stroke
				(width 0.1)
				(type default)
			)
			(layer "F.Fab")
		)
		(fp_line
			(start -0.67945 -0.305054)
			(end -0.12065 -0.305054)
			(stroke
				(width 0.1)
				(type default)
			)
			(layer "F.Fab")
		)
		(pad "1" smd circle
			(at -0.40005 0 180)
			(size 0 0)
			(layers "F.Cu" "F.Mask" "F.Paste")
			(net "GND")
		)
		(pad "2" smd circle
			(at 0.40005 0 180)
			(size 0 0)
			(layers "F.Cu" "F.Mask" "F.Paste")
			(net "PVCCINFAON_CPU0_VREF")
		)
	)
	(footprint ""
		(layer "F.Cu")
		(at 129.75082 -27.348688 -90)
		(property "Reference" "C2285"
			(at 0 0 270)
			(layer "F.SilkS")
			(hide yes)
			(effects
				(font
					(size 1.27 1.27)
				)
			)
		)
		(property "Value" ""
			(at 0 0 270)
			(layer "F.Fab")
			(effects
				(font
					(size 1.27 1.27)
				)
			)
		)
		(duplicate_pad_numbers_are_jumpers no)
		(fp_line
			(start -0.7874 0.4064)
			(end -0.7874 -0.4064)
			(stroke
				(width 0.1524)
				(type default)
			)
			(layer "F.SilkS")
		)
		(fp_line
			(start 0.7874 0.4064)
			(end -0.7874 0.4064)
			(stroke
				(width 0.1524)
				(type default)
			)
			(layer "F.SilkS")
		)
		(fp_line
			(start -0.7874 -0.4064)
			(end 0.7874 -0.4064)
			(stroke
				(width 0.1524)
				(type default)
			)
			(layer "F.SilkS")
		)
		(fp_line
			(start 0.7874 -0.4064)
			(end 0.7874 0.4064)
			(stroke
				(width 0.1524)
				(type default)
			)
			(layer "F.SilkS")
		)
		(fp_line
			(start -0.67945 0.3048)
			(end -0.67945 -0.305054)
			(stroke
				(width 0.1)
				(type default)
			)
			(layer "F.Fab")
		)
		(fp_line
			(start -0.12065 0.3048)
			(end -0.67945 0.3048)
			(stroke
				(width 0.1)
				(type default)
			)
			(layer "F.Fab")
		)
		(fp_line
			(start 0.120396 0.3048)
			(end 0.120396 0.2794)
			(stroke
				(width 0.1)
				(type default)
			)
			(layer "F.Fab")
		)
		(fp_line
			(start 0.67945 0.3048)
			(end 0.120396 0.3048)
			(stroke
				(width 0.1)
				(type default)
			)
			(layer "F.Fab")
		)
		(fp_line
			(start -0.12065 0.2794)
			(end -0.12065 0.3048)
			(stroke
				(width 0.1)
				(type default)
			)
			(layer "F.Fab")
		)
		(fp_line
			(start 0.120396 0.2794)
			(end -0.12065 0.2794)
			(stroke
				(width 0.1)
				(type default)
			)
			(layer "F.Fab")
		)
		(fp_line
			(start -0.12065 -0.2794)
			(end 0.12065 -0.2794)
			(stroke
				(width 0.1)
				(type default)
			)
			(layer "F.Fab")
		)
		(fp_line
			(start 0.12065 -0.2794)
			(end 0.12065 -0.3048)
			(stroke
				(width 0.1)
				(type default)
			)
			(layer "F.Fab")
		)
		(fp_line
			(start 0.12065 -0.3048)
			(end 0.67945 -0.3048)
			(stroke
				(width 0.1)
				(type default)
			)
			(layer "F.Fab")
		)
		(fp_line
			(start 0.67945 -0.3048)
			(end 0.67945 0.3048)
			(stroke
				(width 0.1)
				(type default)
			)
			(layer "F.Fab")
		)
		(fp_line
			(start -0.67945 -0.305054)
			(end -0.12065 -0.305054)
			(stroke
				(width 0.1)
				(type default)
			)
			(layer "F.Fab")
		)
		(fp_line
			(start -0.12065 -0.305054)
			(end -0.12065 -0.2794)
			(stroke
				(width 0.1)
				(type default)
			)
			(layer "F.Fab")
		)
		(pad "1" smd circle
			(at -0.40005 0 270)
			(size 0 0)
			(layers "F.Cu" "F.Mask" "F.Paste")
			(net "P3V3_AUX_USB_BUF")
		)
		(pad "2" smd circle
			(at 0.40005 0 270)
			(size 0 0)
			(layers "F.Cu" "F.Mask" "F.Paste")
			(net "GND")
		)
	)
	(footprint ""
		(layer "F.Cu")
		(at 51.932078 -402.371052 -90)
		(property "Reference" "C713"
			(at 0 0 270)
			(layer "F.SilkS")
			(hide yes)
			(effects
				(font
					(size 1.27 1.27)
				)
			)
		)
		(property "Value" ""
			(at 0 0 270)
			(layer "F.Fab")
			(effects
				(font
					(size 1.27 1.27)
				)
			)
		)
		(duplicate_pad_numbers_are_jumpers no)
		(fp_line
			(start -0.299974 0.150114)
			(end -0.299974 -0.150114)
			(stroke
				(width 0.1)
				(type default)
			)
			(layer "F.Fab")
		)
		(fp_line
			(start 0.299974 0.150114)
			(end -0.299974 0.150114)
			(stroke
				(width 0.1)
				(type default)
			)
			(layer "F.Fab")
		)
		(fp_line
			(start -0.299974 -0.150114)
			(end 0.299974 -0.150114)
			(stroke
				(width 0.1)
				(type default)
			)
			(layer "F.Fab")
		)
		(fp_line
			(start 0.299974 -0.150114)
			(end 0.299974 0.150114)
			(stroke
				(width 0.1)
				(type default)
			)
			(layer "F.Fab")
		)
		(pad "1" smd rect
			(at -0.2667 0 270)
			(size 0.3048 0.381)
			(layers "F.Cu" "F.Mask" "F.Paste")
			(net "P5E_CPU1_PE0_TX_C_DP<14>")
		)
		(pad "2" smd rect
			(at 0.2667 0 270)
			(size 0.3048 0.381)
			(layers "F.Cu" "F.Mask" "F.Paste")
			(net "P5E_CPU1_PE0_TX_DP<14>")
		)
	)
	(footprint ""
		(layer "F.Cu")
		(at 128.401572 -130.002026)
		(property "Reference" "R2703"
			(at 0 0 0)
			(layer "F.SilkS")
			(hide yes)
			(effects
				(font
					(size 1.27 1.27)
				)
			)
		)
		(property "Value" ""
			(at 0 0 0)
			(layer "F.Fab")
			(effects
				(font
					(size 1.27 1.27)
				)
			)
		)
		(duplicate_pad_numbers_are_jumpers no)
		(fp_line
			(start -0.7874 -0.4064)
			(end 0.7874 -0.4064)
			(stroke
				(width 0.1524)
				(type default)
			)
			(layer "F.SilkS")
		)
		(fp_line
			(start -0.7874 0.4064)
			(end -0.7874 -0.4064)
			(stroke
				(width 0.1524)
				(type default)
			)
			(layer "F.SilkS")
		)
		(fp_line
			(start 0.7874 -0.4064)
			(end 0.7874 0.4064)
			(stroke
				(width 0.1524)
				(type default)
			)
			(layer "F.SilkS")
		)
		(fp_line
			(start 0.7874 0.4064)
			(end -0.7874 0.4064)
			(stroke
				(width 0.1524)
				(type default)
			)
			(layer "F.SilkS")
		)
		(fp_line
			(start -0.67945 -0.305054)
			(end -0.12065 -0.305054)
			(stroke
				(width 0.1)
				(type default)
			)
			(layer "F.Fab")
		)
		(fp_line
			(start -0.67945 0.3048)
			(end -0.67945 -0.305054)
			(stroke
				(width 0.1)
				(type default)
			)
			(layer "F.Fab")
		)
		(fp_line
			(start -0.12065 -0.305054)
			(end -0.12065 -0.2794)
			(stroke
				(width 0.1)
				(type default)
			)
			(layer "F.Fab")
		)
		(fp_line
			(start -0.12065 -0.2794)
			(end 0.12065 -0.2794)
			(stroke
				(width 0.1)
				(type default)
			)
			(layer "F.Fab")
		)
		(fp_line
			(start -0.12065 0.2794)
			(end -0.12065 0.3048)
			(stroke
				(width 0.1)
				(type default)
			)
			(layer "F.Fab")
		)
		(fp_line
			(start -0.12065 0.3048)
			(end -0.67945 0.3048)
			(stroke
				(width 0.1)
				(type default)
			)
			(layer "F.Fab")
		)
		(fp_line
			(start 0.120396 0.2794)
			(end -0.12065 0.2794)
			(stroke
				(width 0.1)
				(type default)
			)
			(layer "F.Fab")
		)
		(fp_line
			(start 0.120396 0.3048)
			(end 0.120396 0.2794)
			(stroke
				(width 0.1)
				(type default)
			)
			(layer "F.Fab")
		)
		(fp_line
			(start 0.12065 -0.3048)
			(end 0.67945 -0.3048)
			(stroke
				(width 0.1)
				(type default)
			)
			(layer "F.Fab")
		)
		(fp_line
			(start 0.12065 -0.2794)
			(end 0.12065 -0.3048)
			(stroke
				(width 0.1)
				(type default)
			)
			(layer "F.Fab")
		)
		(fp_line
			(start 0.67945 -0.3048)
			(end 0.67945 0.3048)
			(stroke
				(width 0.1)
				(type default)
			)
			(layer "F.Fab")
		)
		(fp_line
			(start 0.67945 0.3048)
			(end 0.120396 0.3048)
			(stroke
				(width 0.1)
				(type default)
			)
			(layer "F.Fab")
		)
		(pad "1" smd circle
			(at -0.40005 0)
			(size 0 0)
			(layers "F.Cu" "F.Mask" "F.Paste")
			(net "SMB_BMC_SWB_SCL_R4")
		)
		(pad "2" smd circle
			(at 0.40005 0)
			(size 0 0)
			(layers "F.Cu" "F.Mask" "F.Paste")
			(net "SMB_BMC_SWB_SCL")
		)
	)
)
